FILE_TYPE = MULTI_PHYS_TABLE;

PART 'MOSFET_NCH_GDS_ESD_PROTECTED'

{========================================================================================}
:VALUE         | PART_TYPE | MATERIAL | PART_NUMBER       = STANDARD    | LIFECYCLE      | PART_NUMBER       | JEDEC_TYPE                  | DESCRIPTION                                | MANUFTR | MANUF_PN      | RD_CMPLS_LVL | CMPLS_LVL | CLASS | DIP_SMD | FP_ECN           | FROM_PJ        | DATA                         | EE_CHECK_LIST | STATUS | PSL | PREFERENCE | CREATOR | CREATEDAY  ;
{========================================================================================}
 'BSS138'      | 'SMLF'    | 'IC'     | 'BAM01380009'(!)  = ''          | ''             | 'BAM01380009'     |'SOT23_GDSXC'| 'TRANS MOSFET BSS138(50V,300MA,0.35W)'     | 'PJT'   | 'BSS138'      | 'EP(V1)'     | 'EP(V1)'  | 'IC'  | ''      | ''               | 'T2R-YAO-HSUN' | 'PJT_BSS138_rev0.pdf'        | ''            | ''     | ''  | ''         | ''      | '20140122'
 'BSS138'      | 'SMLF'    | 'EMPTY'  | 'BAM01380009'(!)  = ''          | ''             | 'BAM01380009'     |'SOT23_GDSXC'| 'TRANS MOSFET BSS138(50V,300MA,0.35W)'     | 'PJT'   | 'BSS138'      | 'EP(V1)'     | 'EP(V1)'  | 'IC'  | ''      | ''               | 'T2R-YAO-HSUN' | 'PJT_BSS138_rev0.pdf'        | ''            | ''     | ''  | ''         | ''      | '20140122'
 '2N7002K'     | 'SMLF'    | 'IC'     | 'BAM70020002'(!)  = ''          | ''             | 'BAM70020002'     |'SOT23_GDSXC'| 'TR MOSFET 2N7002K(60V,300MA,0.35W)SOT-23' | 'PJT'   | '2N7002K'     | 'EP(V1)'     | 'EP(V1)'  | 'IC'  | ''      | ''               | 'S1F-TONY'     | 'PJT_2N7002K.pdf'            | ''            | ''     | ''  | ''         | ''      | '20140122'
 '2N7002K'     | 'SMLF'    | 'EMPTY'  | 'BAM70020002'(!)  = ''          | ''             | 'BAM70020002'     |'SOT23_GDSXC'| 'TR MOSFET 2N7002K(60V,300MA,0.35W)SOT-23' | 'PJT'   | '2N7002K'     | 'EP(V1)'     | 'EP(V1)'  | 'IC'  | ''      | ''               | 'S1F-TONY'     | 'PJT_2N7002K.pdf'            | ''            | ''     | ''  | ''         | ''      | '20140122'
 '2N7002KW'    | 'SMLF'    | 'IC'     | 'BAM70020041'(!)  = ''          | ''             | 'BAM70020041'     |'SOT323XB'| 'TRANMOS 2N7002KW SOT323(60V, 115MA,0.2W)' | 'PJT'   | '2N7002KW'    | 'EP(V1)'     | 'EP(V1)'  | 'IC'  | ''      | ''               | 'MF1-EDDIE'    | 'PJT_2N7002KW.pdf'           | ''            | ''     | ''  | ''         | ''      | '20140122'
 '2N7002KW'    | 'SMLF'    | 'EMPTY'  | 'BAM70020041'(!)  = ''          | ''             | 'BAM70020041'     |'SOT323XB'| 'TRANMOS 2N7002KW SOT323(60V, 115MA,0.2W)' | 'PJT'   | '2N7002KW'    | 'EP(V1)'     | 'EP(V1)'  | 'IC'  | ''      | ''               | 'MF1-EDDIE'    | 'PJT_2N7002KW.pdf'           | ''            | ''     | ''  | ''         | ''      | '20140122'
 'BSS138BK'    | 'SMLF'    | 'IC'     | 'BAM01380018'(!)  = ''          | ''             | 'BAM01380018'     |'SOT23_GDSXE'| 'TRANS MOSFET BSS138BK(60V,0.35W)SOT23'    | 'NXP'   | 'BSS138BK'    | 'EP(V1)'     | 'EP(V1)'  | 'IC'  | ''      | ''               | 'UH3M-KEVIN'   | 'NXP_BSS138BK.pdf'           | ''            | ''     | ''  | ''         | ''      | '20150814'
 'BSS138BK'    | 'SMLF'    | 'EMPTY'  | 'BAM01380018'(!)  = ''          | ''             | 'BAM01380018'     |'SOT23_GDSXE'| 'TRANS MOSFET BSS138BK(60V,0.35W)SOT23'    | 'NXP'   | 'BSS138BK'    | 'EP(V1)'     | 'EP(V1)'  | 'IC'  | ''      | ''               | 'UH3M-KEVIN'   | 'NXP_BSS138BK.pdf'           | ''            | ''     | ''  | ''         | ''      | '20150814'
 'AO3416'      | 'SMLF'    | 'IC'     | 'BAM34160007'(!)  = ''          | ''             | 'BAM34160007'     |'SOT23_GDSXA'| 'TRANS MOSFET AO3416(20V,6.5A,1.4W)SOT23'  | 'AOS'   | 'AO3416'      | 'EP(V1)'     | 'EP(V1)'  | 'IC'  | ''      | ''               | 'MF1-TONY'     | 'AOS_AO3416.pdf'             | ''            | ''     | ''  | ''         | ''      | '20160223'
 'AO3416'      | 'SMLF'    | 'EMPTY'  | 'BAM34160007'(!)  = ''          | ''             | 'BAM34160007'     |'SOT23_GDSXA'| 'TRANS MOSFET AO3416(20V,6.5A,1.4W)SOT23'  | 'AOS'   | 'AO3416'      | 'EP(V1)'     | 'EP(V1)'  | 'IC'  | ''      | ''               | 'MF1-TONY'     | 'AOS_AO3416.pdf'             | ''            | ''     | ''  | ''         | ''      | '20160223'
 'DMG6968UQ-7' | 'SMLF'    | 'IC'     | 'BAM69680001'(!)  = ''          | ''             | 'BAM69680001'     |'SOT23_GDSXC'| 'TRANS MOS DMG6968UQ-7(20V,6.5A,1.3W)AEC'  | 'DDS'   | 'DMG6968UQ-7' | 'EP(V1)'     | ''        | 'IC'  | ''      | ''               | 'T2HV-RONNY'   | 'DDS_DMG6968UQ-7_REV6-2.pdf' | ''            | ''     | ''  | ''         | ''      | '20160317'
 'DMG6968UQ-7' | 'SMLF'    | 'EMPTY'  | 'BAM69680001'(!)  = ''          | ''             | 'BAM69680001'     |'SOT23_GDSXC'| 'TRANS MOS DMG6968UQ-7(20V,6.5A,1.3W)AEC'  | 'DDS'   | 'DMG6968UQ-7' | 'EP(V1)'     | ''        | 'IC'  | ''      | ''               | 'T2HV-RONNY'   | 'DDS_DMG6968UQ-7_REV6-2.pdf' | ''            | ''     | ''  | ''         | ''      | '20160317'
 'DMN61D9UW-7' | 'SMLF'    | 'IC'     | 'BAM61D90001'(!)  = 'Potential' | 'End of Life'  | 'BAM61D90001'     |'SOT323_GDS_2-15X1-3XA_EOL'| 'TRANS MOS DMN61D9UW-7(60V,0.34A,0.32W)'   | 'DDS'   | 'DMN61D9UW-7' | 'EP(V1)'     | ''        | 'IC'  | ''      | ''               | 'T2MK-FRANK'   | 'DDS_DMN61D9UW-7.pdf'        | ''            | ''     | ''  | ''         | ''      | '20171213'
 'DMN61D9UW-7' | 'SMLF'    | 'EMPTY'  | 'BAM61D90001'(!)  = 'Potential' | 'End of Life'  | 'BAM61D90001'     |'SOT323_GDS_2-15X1-3XA_EOL'| 'TRANS MOS DMN61D9UW-7(60V,0.34A,0.32W)'   | 'DDS'   | 'DMN61D9UW-7' | 'EP(V1)'     | ''        | 'IC'  | ''      | ''               | 'T2MK-FRANK'   | 'DDS_DMN61D9UW-7.pdf'        | ''            | ''     | ''  | ''         | ''      | '20171213'
 'DMN53D0L-7'  | 'SMLF'    | 'IC'     | 'BAM53D00000'(!)  = ''          | ''             | 'BAM53D00000'     |'SOT23_GDSXC'| 'TRANS MOSFET DMN53D0L-7(50V,0.5A,0.5W)'   | 'DDS'   | 'DMN53D0L-7'  | 'EP(V1)'     | 'EP(V1)'  | 'IC'  | ''      | ''               | 'JBP-JACK'     | 'DDS_DMN53D0L-7.pdf'         | ''            | ''     | ''  | ''         | ''      | '20190104'
 'DMN53D0L-7'  | 'SMLF'    | 'EMPTY'  | 'BAM53D00000'(!)  = ''          | ''             | 'BAM53D00000'     |'SOT23_GDSXC'| 'TRANS MOSFET DMN53D0L-7(50V,0.5A,0.5W)'   | 'DDS'   | 'DMN53D0L-7'  | 'EP(V1)'     | 'EP(V1)'  | 'IC'  | ''      | ''               | 'JBP-JACK'     | 'DDS_DMN53D0L-7.pdf'         | ''            | ''     | ''  | ''         | ''      | '20190104'
 '2N7002KTB'   | 'SMLF'    | 'IC'     | 'BAN70020007'(!)  = ''          | ''             | 'BAN70020007'     |'SOT523_GDS_1-6X1-2'| 'TRANS MOS 2N7002KTB (60V,0.115A,0.2W)'    | 'PJT'   | '2N7002KTB'   | 'EP(V1)'     | 'EP(V1)'  | 'IC'  | ''      | ''               | 'S5Z-ERIC'     | 'PJT_2N7002KTB.pdf'          | ''            | ''     | ''  | ''         | ''      | '20200714'
 '2N7002KTB'   | 'SMLF'    | 'EMPTY'  | 'BAN70020007'(!)  = ''          | ''             | 'BAN70020007'     |'SOT523_GDS_1-6X1-2'| 'TRANS MOS 2N7002KTB (60V,0.115A,0.2W)'    | 'PJT'   | '2N7002KTB'   | 'EP(V1)'     | 'EP(V1)'  | 'IC'  | ''      | ''               | 'S5Z-ERIC'     | 'PJT_2N7002KTB.pdf'          | ''            | ''     | ''  | ''         | ''      | '20200714'
 'PJC138K'     | 'SMLF'    | 'IC'     | 'BAM138K0002'(!)  = ''          | ''             | 'BAM138K0002'     |'SOT323_GDS_2X1-25'| 'TRANS MOSFET PJC138K(50V,0.36A,0.236W)'   | 'PJT'   | 'PJC138K'     | 'EP(V1)'     | 'EP(V1)'  | 'IC'  | ''      | ''               | 'S9T-CHI-LIN'  | 'PJT_2N7002KTB.pdf'          | ''            | ''     | ''  | ''         | ''      | '20210331'
 'PJC138K'     | 'SMLF'    | 'EMPTY'  | 'BAM138K0002'(!)  = ''          | ''             | 'BAM138K0002'     |'SOT323_GDS_2X1-25'| 'TRANS MOSFET PJC138K(50V,0.36A,0.236W)'   | 'PJT'   | 'PJC138K'     | 'EP(V1)'     | 'EP(V1)'  | 'IC'  | ''      | ''               | 'S9T-CHI-LIN'  | 'PJT_2N7002KTB.pdf'          | ''            | ''     | ''  | ''         | ''      | '20210331'
 'DMN53D0U-7'  | 'SMLF'    | 'IC'     | 'BAM3D0U0000'(!)  = ''          | ''             | 'BAM3D0U0000'     |'SOT23_GDSXC'| 'TRANS MOS DMN53D0U-7(50V,0.3/0.2A,0.52W)' | 'DDS'   | 'DMN53D0U-7'  | 'EP(V1)'     | ''        | 'IC'  | ''      | ''               | 'S8G-MICHAEL'  | 'DDS_DMN53D0U-7.pdf'         | ''            | ''     | ''  | ''         | ''      | '20230321'
 'DMN53D0U-7'  | 'SMLF'    | 'EMPTY'  | 'BAM3D0U0000'(!)  = ''          | ''             | 'BAM3D0U0000'     |'SOT23_GDSXC'| 'TRANS MOS DMN53D0U-7(50V,0.3/0.2A,0.52W)' | 'DDS'   | 'DMN53D0U-7'  | 'EP(V1)'     | ''        | 'IC'  | ''      | ''               | 'S8G-MICHAEL'  | 'DDS_DMN53D0U-7.pdf'         | ''            | ''     | ''  | ''         | ''      | '20230321'
 'DMN53D0L-7'  | 'SMLF'    | 'IC'     | 'BAM53D00000SEL1'(!) = ''          | ''             | 'BAM53D00000SEL1' |'SOT23_GDSXC'| 'TRANS MOS DMN53D0L-7(50V,0.5A,0.5W)SELA'  | 'DDS'   | 'DMN53D0L-7'  | 'EP(V1)'     | 'EP(V1)'  | 'IC'  | ''      | 'SEL_15QPN.xlsx' | 'JBP-JACK'     | 'DDS_DMN53D0L-7.pdf'         | ''            | ''     | ''  | ''         | ''      | '20230626'
 'DMN53D0L-7'  | 'SMLF'    | 'EMPTY'  | 'BAM53D00000SEL1'(!) = ''          | ''             | 'BAM53D00000SEL1' |'SOT23_GDSXC'| 'TRANS MOS DMN53D0L-7(50V,0.5A,0.5W)SELA'  | 'DDS'   | 'DMN53D0L-7'  | 'EP(V1)'     | 'EP(V1)'  | 'IC'  | ''      | 'SEL_15QPN.xlsx' | 'JBP-JACK'     | 'DDS_DMN53D0L-7.pdf'         | ''            | ''     | ''  | ''         | ''      | '20230626'
 '2N7002KW'    | 'SMLF'    | 'IC'     | 'BAM70020041SEL1'(!) = ''          | ''             | 'BAM70020041SEL1' |'SOT323XB'| 'TRANMOS 2N7002KWSOT323(60V115MA0.2W)SELA' | 'PJT'   | '2N7002KW'    | 'EP(V1)'     | 'EP(V1)'  | 'IC'  | ''      | 'SEL_15QPN.xlsx' | 'MF1-EDDIE'    | 'PJT_2N7002KW.pdf'           | ''            | ''     | ''  | ''         | ''      | '20230626'
 '2N7002KW'    | 'SMLF'    | 'EMPTY'  | 'BAM70020041SEL1'(!) = ''          | ''             | 'BAM70020041SEL1' |'SOT323XB'| 'TRANMOS 2N7002KWSOT323(60V115MA0.2W)SELA' | 'PJT'   | '2N7002KW'    | 'EP(V1)'     | 'EP(V1)'  | 'IC'  | ''      | 'SEL_15QPN.xlsx' | 'MF1-EDDIE'    | 'PJT_2N7002KW.pdf'           | ''            | ''     | ''  | ''         | ''      | '20230626'
 'AOSS32334S'  | 'SMLF'    | 'IC'     | 'BAM334S0000'(!)  = ''          | ''             | 'BAM334S0000'     |'SOT23_GDSXA'| 'TRANS MOS AOSS32334S(30V,6.2A,1.3W)SOT23' | 'AOS'   | 'AOSS32334S'  | 'EP(V1)'     | ''        | 'IC'  | ''      | ''               | 'F0M-CHRIS'    | 'AOS_AOSS32334S.pdf'         | ''            | ''     | ''  | ''         | ''      | '20230704'
 'AOSS32334S'  | 'SMLF'    | 'EMPTY'  | 'BAM334S0000'(!)  = ''          | ''             | 'BAM334S0000'     |'SOT23_GDSXA'| 'TRANS MOS AOSS32334S(30V,6.2A,1.3W)SOT23' | 'AOS'   | 'AOSS32334S'  | 'EP(V1)'     | ''        | 'IC'  | ''      | ''               | 'F0M-CHRIS'    | 'AOS_AOSS32334S.pdf'         | ''            | ''     | ''  | ''         | ''      | '20230704'
 'PJA138K'     | 'SMLF'    | 'IC'     | 'BAM138K0001'(!)  = ''          | ''             | 'BAM138K0001'     |'SOT23_GDS_2-92X1-3XB'| 'TRANS MOSFET PJA138K(50V,0.5A,0.5W)'      | 'PJT'   | 'PJA138K'     | 'EP(V1)'     | 'EP(V1)'  | 'IC'  | ''      | ''               | 'T6H-WILLY'    | 'PJT_PJA138K.pdf'            | ''            | ''     | ''  | ''         | ''      | '20230706'
 'PJA138K'     | 'SMLF'    | 'EMPTY'  | 'BAM138K0001'(!)  = ''          | ''             | 'BAM138K0001'     |'SOT23_GDS_2-92X1-3XB'| 'TRANS MOSFET PJA138K(50V,0.5A,0.5W)'      | 'PJT'   | 'PJA138K'     | 'EP(V1)'     | 'EP(V1)'  | 'IC'  | ''      | ''               | 'T6H-WILLY'    | 'PJT_PJA138K.pdf'            | ''            | ''     | ''  | ''         | ''      | '20230706'
 'PJA138K'     | 'SMLF'    | 'IC'     | 'BAM138K0001SEL1'(!) = ''          | ''               | 'BAM138K0001SEL1' |'SOT23_GDS_2-92X1-3XB'| 'TRANS MOSFET PJA138K(50V,0.5A,0.5W)SELA'  | 'PJT'   | 'PJA138K'     | 'EP(V1)'     | 'EP(V1)'  | 'IC'  | ''      | ''               | 'S8ZE-JASON'   | 'PJT_PJA138K.pdf'            | ''            | ''     | ''  | ''         | ''      | '20230818'
 'PJA138K'     | 'SMLF'    | 'EMPTY'  | 'BAM138K0001SEL1'(!) = ''          | ''               | 'BAM138K0001SEL1' |'SOT23_GDS_2-92X1-3XB'| 'TRANS MOSFET PJA138K(50V,0.5A,0.5W)SELA'  | 'PJT'   | 'PJA138K'     | 'EP(V1)'     | 'EP(V1)'  | 'IC'  | ''      | ''               | 'S8ZE-JASON'   | 'PJT_PJA138K.pdf'            | ''            | ''     | ''  | ''         | ''      | '20230818'

END_PART

END.

